(kicad_pcb
	(version 20260206)
	(generator "pcbnew")
	(generator_version "10.0")
	(general
		(thickness 1.6)
		(legacy_teardrops no)
	)
	(paper "A4")
	(title_block
		(title "03242023_DA0F0TMBIJ0_F0T_Motherboard_J_brd_V01_OCP.brd")
		(comment 1 "Grand Teton / footprints 1300-1300 of 6105")
	)
	(layers
		(0 "F.Cu" signal "TOP")
		(4 "In1.Cu" signal "GND")
		(6 "In2.Cu" signal "IN1")
		(8 "In3.Cu" signal "GND1")
		(10 "In4.Cu" signal "IN2")
		(12 "In5.Cu" signal "GND2")
		(14 "In6.Cu" signal "IN3")
		(16 "In7.Cu" signal "GND3")
		(18 "In8.Cu" signal "VCC")
		(20 "In9.Cu" signal "VCC1")
		(22 "In10.Cu" signal "GND4")
		(24 "In11.Cu" signal "IN4")
		(26 "In12.Cu" signal "GND5")
		(28 "In13.Cu" signal "IN5")
		(30 "In14.Cu" signal "GND6")
		(32 "In15.Cu" signal "IN6")
		(34 "In16.Cu" signal "GND7")
		(2 "B.Cu" signal "BOTTOM")
		(9 "F.Adhes" user "F.Adhesive")
		(11 "B.Adhes" user "B.Adhesive")
		(13 "F.Paste" user "Package Geometry/Pastemask Top")
		(15 "B.Paste" user "Package Geometry/Pastemask Bottom")
		(5 "F.SilkS" user "Ref Des/Silkscreen Top")
		(7 "B.SilkS" user "Ref Des/Silkscreen Bottom")
		(1 "F.Mask" user "Board Geometry/Soldermask Top")
		(3 "B.Mask" user "Board Geometry/Soldermask Bottom")
		(17 "Dwgs.User" user "User.Drawings")
		(19 "Cmts.User" user "User.Comments")
		(21 "Eco1.User" user "User.Eco1")
		(23 "Eco2.User" user "User.Eco2")
		(25 "Edge.Cuts" user "Board Geometry/Outline")
		(27 "Margin" user)
		(31 "F.CrtYd" user "Package Geometry/Place Bound Top")
		(29 "B.CrtYd" user "Package Geometry/Place Bound Bottom")
		(35 "F.Fab" user "Ref Des/Assembly Top")
		(33 "B.Fab" user "Ref Des/Assembly Bottom")
	)
	(footprint ""
		(layer "F.Cu")
		(at 181.710584 -344.7796 -90)
		(property "Reference" "PL12"
			(at -3.214878 -4.197096 0)
			(unlocked yes)
			(layer "F.SilkS")
			(effects
				(font
					(size 0.7874 0.5842)
					(thickness 0.1524)
				)
				(justify left)
			)
		)
		(property "Value" ""
			(at 0 0 270)
			(layer "F.Fab")
			(effects
				(font
					(size 1.27 1.27)
				)
			)
		)
		(duplicate_pad_numbers_are_jumpers no)
		(fp_line
			(start -4.99999 3.750056)
			(end -4.99999 2.2479)
			(stroke
				(width 0.1524)
				(type default)
			)
			(layer "F.SilkS")
		)
		(fp_line
			(start 0 3.750056)
			(end -4.99999 3.750056)
			(stroke
				(width 0.1524)
				(type default)
			)
			(layer "F.SilkS")
		)
		(fp_line
			(start 4.99999 3.750056)
			(end 0 3.750056)
			(stroke
				(width 0.1524)
				(type default)
			)
			(layer "F.SilkS")
		)
		(fp_line
			(start 4.99999 2.2352)
			(end 4.99999 3.750056)
			(stroke
				(width 0.1524)
				(type default)
			)
			(layer "F.SilkS")
		)
		(fp_line
			(start -4.99999 -2.2479)
			(end -4.99999 -3.750056)
			(stroke
				(width 0.1524)
				(type default)
			)
			(layer "F.SilkS")
		)
		(fp_line
			(start -4.99999 -3.750056)
			(end 4.99999 -3.750056)
			(stroke
				(width 0.1524)
				(type default)
			)
			(layer "F.SilkS")
		)
		(fp_line
			(start 4.99999 -3.750056)
			(end 4.99999 -2.2479)
			(stroke
				(width 0.1524)
				(type default)
			)
			(layer "F.SilkS")
		)
		(fp_line
			(start -4.99999 3.750056)
			(end -4.99999 -3.750056)
			(stroke
				(width 0.1)
				(type default)
			)
			(layer "F.Fab")
		)
		(fp_line
			(start 0 3.750056)
			(end -4.99999 3.750056)
			(stroke
				(width 0.1)
				(type default)
			)
			(layer "F.Fab")
		)
		(fp_line
			(start 4.99999 3.750056)
			(end 0 3.750056)
			(stroke
				(width 0.1)
				(type default)
			)
			(layer "F.Fab")
		)
		(fp_line
			(start -4.99999 -3.750056)
			(end 4.99999 -3.750056)
			(stroke
				(width 0.1)
				(type default)
			)
			(layer "F.Fab")
		)
		(fp_line
			(start 4.99999 -3.750056)
			(end 4.99999 3.750056)
			(stroke
				(width 0.1)
				(type default)
			)
			(layer "F.Fab")
		)
		(pad "1" smd rect
			(at -3.299968 0 270)
			(size 3.302 4.2164)
			(layers "F.Cu" "F.Mask" "F.Paste")
			(net "SW_PVCCFA_EHV_FIVRA_CPU1_SW3")
		)
		(pad "2" smd rect
			(at 3.299968 0 270)
			(size 3.302 4.2164)
			(layers "F.Cu" "F.Mask" "F.Paste")
			(net "PVCCFA_EHV_FIVRA_CPU1")
		)
	)
)
